(kicad_pcb
	(version 20260206)
	(generator "pcbnew")
	(generator_version "10.0")
	(general
		(thickness 1.6)
		(legacy_teardrops no)
	)
	(paper "A4")
	(title_block
		(title "01162023_DA0F0TEBIF0_F0T_Expander_BD_F_brd_V02_OCP.brd")
		(comment 1 "Grand Teton / footprints 2743-2748 of 9728")
	)
	(layers
		(0 "F.Cu" signal "TOP")
		(4 "In1.Cu" signal "GND")
		(6 "In2.Cu" signal "VCC")
		(8 "In3.Cu" signal "VCC1")
		(10 "In4.Cu" signal "GND1")
		(12 "In5.Cu" signal "IN1")
		(14 "In6.Cu" signal "GND2")
		(16 "In7.Cu" signal "IN2")
		(18 "In8.Cu" signal "GND3")
		(20 "In9.Cu" signal "IN3")
		(22 "In10.Cu" signal "GND4")
		(24 "In11.Cu" signal "IN4")
		(26 "In12.Cu" signal "GND5")
		(28 "In13.Cu" signal "IN5")
		(30 "In14.Cu" signal "GND6")
		(32 "In15.Cu" signal "IN6")
		(34 "In16.Cu" signal "GND7")
		(2 "B.Cu" signal "BOTTOM")
		(9 "F.Adhes" user "F.Adhesive")
		(11 "B.Adhes" user "B.Adhesive")
		(13 "F.Paste" user "Package Geometry/Pastemask Top")
		(15 "B.Paste" user "Package Geometry/Pastemask Bottom")
		(5 "F.SilkS" user "Ref Des/Silkscreen Top")
		(7 "B.SilkS" user "Ref Des/Silkscreen Bottom")
		(1 "F.Mask" user "Board Geometry/Soldermask Top")
		(3 "B.Mask" user "Board Geometry/Soldermask Bottom")
		(17 "Dwgs.User" user "User.Drawings")
		(19 "Cmts.User" user "User.Comments")
		(21 "Eco1.User" user "User.Eco1")
		(23 "Eco2.User" user "User.Eco2")
		(25 "Edge.Cuts" user "Board Geometry/Outline")
		(27 "Margin" user)
		(31 "F.CrtYd" user "Package Geometry/Place Bound Top")
		(29 "B.CrtYd" user "Package Geometry/Place Bound Bottom")
		(35 "F.Fab" user "Ref Des/Assembly Top")
		(33 "B.Fab" user "Ref Des/Assembly Bottom")
	)
	(footprint ""
		(layer "F.Cu")
		(at 302.377856 -83.667092 180)
		(property "Reference" "R487"
			(at 0 0 180)
			(layer "F.SilkS")
			(hide yes)
			(effects
				(font
					(size 1.27 1.27)
				)
			)
		)
		(property "Value" ""
			(at 0 0 180)
			(layer "F.Fab")
			(effects
				(font
					(size 1.27 1.27)
				)
			)
		)
		(duplicate_pad_numbers_are_jumpers no)
		(fp_line
			(start 0.7874 0.4064)
			(end -0.7874 0.4064)
			(stroke
				(width 0.1524)
				(type default)
			)
			(layer "F.SilkS")
		)
		(fp_line
			(start 0.7874 -0.4064)
			(end 0.7874 0.4064)
			(stroke
				(width 0.1524)
				(type default)
			)
			(layer "F.SilkS")
		)
		(fp_line
			(start -0.7874 0.4064)
			(end -0.7874 -0.4064)
			(stroke
				(width 0.1524)
				(type default)
			)
			(layer "F.SilkS")
		)
		(fp_line
			(start -0.7874 -0.4064)
			(end 0.7874 -0.4064)
			(stroke
				(width 0.1524)
				(type default)
			)
			(layer "F.SilkS")
		)
		(fp_line
			(start 0.67945 0.3048)
			(end 0.120396 0.3048)
			(stroke
				(width 0.1)
				(type default)
			)
			(layer "F.Fab")
		)
		(fp_line
			(start 0.67945 -0.3048)
			(end 0.67945 0.3048)
			(stroke
				(width 0.1)
				(type default)
			)
			(layer "F.Fab")
		)
		(fp_line
			(start 0.12065 -0.2794)
			(end 0.12065 -0.3048)
			(stroke
				(width 0.1)
				(type default)
			)
			(layer "F.Fab")
		)
		(fp_line
			(start 0.12065 -0.3048)
			(end 0.67945 -0.3048)
			(stroke
				(width 0.1)
				(type default)
			)
			(layer "F.Fab")
		)
		(fp_line
			(start 0.120396 0.3048)
			(end 0.120396 0.2794)
			(stroke
				(width 0.1)
				(type default)
			)
			(layer "F.Fab")
		)
		(fp_line
			(start 0.120396 0.2794)
			(end -0.12065 0.2794)
			(stroke
				(width 0.1)
				(type default)
			)
			(layer "F.Fab")
		)
		(fp_line
			(start -0.12065 0.3048)
			(end -0.67945 0.3048)
			(stroke
				(width 0.1)
				(type default)
			)
			(layer "F.Fab")
		)
		(fp_line
			(start -0.12065 0.2794)
			(end -0.12065 0.3048)
			(stroke
				(width 0.1)
				(type default)
			)
			(layer "F.Fab")
		)
		(fp_line
			(start -0.12065 -0.2794)
			(end 0.12065 -0.2794)
			(stroke
				(width 0.1)
				(type default)
			)
			(layer "F.Fab")
		)
		(fp_line
			(start -0.12065 -0.305054)
			(end -0.12065 -0.2794)
			(stroke
				(width 0.1)
				(type default)
			)
			(layer "F.Fab")
		)
		(fp_line
			(start -0.67945 0.3048)
			(end -0.67945 -0.305054)
			(stroke
				(width 0.1)
				(type default)
			)
			(layer "F.Fab")
		)
		(fp_line
			(start -0.67945 -0.305054)
			(end -0.12065 -0.305054)
			(stroke
				(width 0.1)
				(type default)
			)
			(layer "F.Fab")
		)
		(pad "1" smd circle
			(at -0.40005 0 180)
			(size 0 0)
			(layers "F.Cu" "F.Mask" "F.Paste")
			(net "SMB_BIC_I2C6_MUX_FRU_R_SCL")
		)
		(pad "2" smd circle
			(at 0.40005 0 180)
			(size 0 0)
			(layers "F.Cu" "F.Mask" "F.Paste")
			(net "SMB_BMC_FRU_SCL")
		)
	)
	(footprint ""
		(layer "F.Cu")
		(at 203.877418 -309.791354 135)
		(property "Reference" "R1310"
			(at 0 0 135)
			(layer "F.SilkS")
			(hide yes)
			(effects
				(font
					(size 1.27 1.27)
				)
			)
		)
		(property "Value" ""
			(at 0 0 135)
			(layer "F.Fab")
			(effects
				(font
					(size 1.27 1.27)
				)
			)
		)
		(duplicate_pad_numbers_are_jumpers no)
		(fp_line
			(start 0.787389 -0.406267)
			(end 0.787389 0.406267)
			(stroke
				(width 0.1524)
				(type default)
			)
			(layer "F.SilkS")
		)
		(fp_line
			(start 0.787389 0.406267)
			(end -0.787389 0.406267)
			(stroke
				(width 0.1524)
				(type default)
			)
			(layer "F.SilkS")
		)
		(fp_line
			(start -0.787389 -0.406267)
			(end 0.787389 -0.406267)
			(stroke
				(width 0.1524)
				(type default)
			)
			(layer "F.SilkS")
		)
		(fp_line
			(start -0.787389 0.406267)
			(end -0.787389 -0.406267)
			(stroke
				(width 0.1524)
				(type default)
			)
			(layer "F.SilkS")
		)
		(fp_line
			(start 0.679446 -0.30479)
			(end 0.679446 0.30479)
			(stroke
				(width 0.1)
				(type default)
			)
			(layer "F.Fab")
		)
		(fp_line
			(start 0.120515 -0.30479)
			(end 0.679446 -0.30479)
			(stroke
				(width 0.1)
				(type default)
			)
			(layer "F.Fab")
		)
		(fp_line
			(start 0.120695 -0.279466)
			(end 0.120515 -0.30479)
			(stroke
				(width 0.1)
				(type default)
			)
			(layer "F.Fab")
		)
		(fp_line
			(start 0.679446 0.30479)
			(end 0.120515 0.30479)
			(stroke
				(width 0.1)
				(type default)
			)
			(layer "F.Fab")
		)
		(fp_line
			(start -0.120695 -0.304969)
			(end -0.120695 -0.279466)
			(stroke
				(width 0.1)
				(type default)
			)
			(layer "F.Fab")
		)
		(fp_line
			(start -0.120695 -0.279466)
			(end 0.120695 -0.279466)
			(stroke
				(width 0.1)
				(type default)
			)
			(layer "F.Fab")
		)
		(fp_line
			(start 0.120335 0.279466)
			(end -0.120695 0.279466)
			(stroke
				(width 0.1)
				(type default)
			)
			(layer "F.Fab")
		)
		(fp_line
			(start 0.120515 0.30479)
			(end 0.120335 0.279466)
			(stroke
				(width 0.1)
				(type default)
			)
			(layer "F.Fab")
		)
		(fp_line
			(start -0.679446 -0.305149)
			(end -0.120695 -0.304969)
			(stroke
				(width 0.1)
				(type default)
			)
			(layer "F.Fab")
		)
		(fp_line
			(start -0.120695 0.279466)
			(end -0.120515 0.30479)
			(stroke
				(width 0.1)
				(type default)
			)
			(layer "F.Fab")
		)
		(fp_line
			(start -0.120515 0.30479)
			(end -0.679446 0.30479)
			(stroke
				(width 0.1)
				(type default)
			)
			(layer "F.Fab")
		)
		(fp_line
			(start -0.679446 0.30479)
			(end -0.679446 -0.305149)
			(stroke
				(width 0.1)
				(type default)
			)
			(layer "F.Fab")
		)
		(pad "1" smd circle
			(at -0.40005 0 135)
			(size 0 0)
			(layers "F.Cu" "F.Mask" "F.Paste")
			(net "PEX1_SPARE7")
		)
		(pad "2" smd circle
			(at 0.40005 0 135)
			(size 0 0)
			(layers "F.Cu" "F.Mask" "F.Paste")
			(net "P1V8_PEX")
		)
	)
	(footprint ""
		(layer "F.Cu")
		(at 236.4486 -116.04752 90)
		(property "Reference" "PR6897"
			(at 0 0 90)
			(layer "F.SilkS")
			(hide yes)
			(effects
				(font
					(size 1.27 1.27)
				)
			)
		)
		(property "Value" ""
			(at 0 0 90)
			(layer "F.Fab")
			(effects
				(font
					(size 1.27 1.27)
				)
			)
		)
		(duplicate_pad_numbers_are_jumpers no)
		(fp_line
			(start 0.7874 -0.4064)
			(end 0.7874 0.4064)
			(stroke
				(width 0.1524)
				(type default)
			)
			(layer "F.SilkS")
		)
		(fp_line
			(start -0.7874 -0.4064)
			(end 0.7874 -0.4064)
			(stroke
				(width 0.1524)
				(type default)
			)
			(layer "F.SilkS")
		)
		(fp_line
			(start 0.7874 0.4064)
			(end -0.7874 0.4064)
			(stroke
				(width 0.1524)
				(type default)
			)
			(layer "F.SilkS")
		)
		(fp_line
			(start -0.7874 0.4064)
			(end -0.7874 -0.4064)
			(stroke
				(width 0.1524)
				(type default)
			)
			(layer "F.SilkS")
		)
		(fp_line
			(start -0.12065 -0.305054)
			(end -0.12065 -0.2794)
			(stroke
				(width 0.1)
				(type default)
			)
			(layer "F.Fab")
		)
		(fp_line
			(start -0.67945 -0.305054)
			(end -0.12065 -0.305054)
			(stroke
				(width 0.1)
				(type default)
			)
			(layer "F.Fab")
		)
		(fp_line
			(start 0.67945 -0.3048)
			(end 0.67945 0.3048)
			(stroke
				(width 0.1)
				(type default)
			)
			(layer "F.Fab")
		)
		(fp_line
			(start 0.12065 -0.3048)
			(end 0.67945 -0.3048)
			(stroke
				(width 0.1)
				(type default)
			)
			(layer "F.Fab")
		)
		(fp_line
			(start 0.12065 -0.2794)
			(end 0.12065 -0.3048)
			(stroke
				(width 0.1)
				(type default)
			)
			(layer "F.Fab")
		)
		(fp_line
			(start -0.12065 -0.2794)
			(end 0.12065 -0.2794)
			(stroke
				(width 0.1)
				(type default)
			)
			(layer "F.Fab")
		)
		(fp_line
			(start 0.120396 0.2794)
			(end -0.12065 0.2794)
			(stroke
				(width 0.1)
				(type default)
			)
			(layer "F.Fab")
		)
		(fp_line
			(start -0.12065 0.2794)
			(end -0.12065 0.3048)
			(stroke
				(width 0.1)
				(type default)
			)
			(layer "F.Fab")
		)
		(fp_line
			(start 0.67945 0.3048)
			(end 0.120396 0.3048)
			(stroke
				(width 0.1)
				(type default)
			)
			(layer "F.Fab")
		)
		(fp_line
			(start 0.120396 0.3048)
			(end 0.120396 0.2794)
			(stroke
				(width 0.1)
				(type default)
			)
			(layer "F.Fab")
		)
		(fp_line
			(start -0.12065 0.3048)
			(end -0.67945 0.3048)
			(stroke
				(width 0.1)
				(type default)
			)
			(layer "F.Fab")
		)
		(fp_line
			(start -0.67945 0.3048)
			(end -0.67945 -0.305054)
			(stroke
				(width 0.1)
				(type default)
			)
			(layer "F.Fab")
		)
		(pad "1" smd circle
			(at -0.40005 0 90)
			(size 0 0)
			(layers "F.Cu" "F.Mask" "F.Paste")
			(net "P12V_NIC3_CO_ISET")
		)
		(pad "2" smd circle
			(at 0.40005 0 90)
			(size 0 0)
			(layers "F.Cu" "F.Mask" "F.Paste")
			(net "P12V_NIC3_CO_ISET_R")
		)
	)
	(footprint ""
		(layer "F.Cu")
		(at 338.074 -167.005 180)
		(property "Reference" "R4772"
			(at 0 0 180)
			(layer "F.SilkS")
			(hide yes)
			(effects
				(font
					(size 1.27 1.27)
				)
			)
		)
		(property "Value" ""
			(at 0 0 180)
			(layer "F.Fab")
			(effects
				(font
					(size 1.27 1.27)
				)
			)
		)
		(duplicate_pad_numbers_are_jumpers no)
		(fp_line
			(start 0.7874 0.4064)
			(end -0.7874 0.4064)
			(stroke
				(width 0.1524)
				(type default)
			)
			(layer "F.SilkS")
		)
		(fp_line
			(start 0.7874 -0.4064)
			(end 0.7874 0.4064)
			(stroke
				(width 0.1524)
				(type default)
			)
			(layer "F.SilkS")
		)
		(fp_line
			(start -0.7874 0.4064)
			(end -0.7874 -0.4064)
			(stroke
				(width 0.1524)
				(type default)
			)
			(layer "F.SilkS")
		)
		(fp_line
			(start -0.7874 -0.4064)
			(end 0.7874 -0.4064)
			(stroke
				(width 0.1524)
				(type default)
			)
			(layer "F.SilkS")
		)
		(fp_line
			(start 0.67945 0.3048)
			(end 0.120396 0.3048)
			(stroke
				(width 0.1)
				(type default)
			)
			(layer "F.Fab")
		)
		(fp_line
			(start 0.67945 -0.3048)
			(end 0.67945 0.3048)
			(stroke
				(width 0.1)
				(type default)
			)
			(layer "F.Fab")
		)
		(fp_line
			(start 0.12065 -0.2794)
			(end 0.12065 -0.3048)
			(stroke
				(width 0.1)
				(type default)
			)
			(layer "F.Fab")
		)
		(fp_line
			(start 0.12065 -0.3048)
			(end 0.67945 -0.3048)
			(stroke
				(width 0.1)
				(type default)
			)
			(layer "F.Fab")
		)
		(fp_line
			(start 0.120396 0.3048)
			(end 0.120396 0.2794)
			(stroke
				(width 0.1)
				(type default)
			)
			(layer "F.Fab")
		)
		(fp_line
			(start 0.120396 0.2794)
			(end -0.12065 0.2794)
			(stroke
				(width 0.1)
				(type default)
			)
			(layer "F.Fab")
		)
		(fp_line
			(start -0.12065 0.3048)
			(end -0.67945 0.3048)
			(stroke
				(width 0.1)
				(type default)
			)
			(layer "F.Fab")
		)
		(fp_line
			(start -0.12065 0.2794)
			(end -0.12065 0.3048)
			(stroke
				(width 0.1)
				(type default)
			)
			(layer "F.Fab")
		)
		(fp_line
			(start -0.12065 -0.2794)
			(end 0.12065 -0.2794)
			(stroke
				(width 0.1)
				(type default)
			)
			(layer "F.Fab")
		)
		(fp_line
			(start -0.12065 -0.305054)
			(end -0.12065 -0.2794)
			(stroke
				(width 0.1)
				(type default)
			)
			(layer "F.Fab")
		)
		(fp_line
			(start -0.67945 0.3048)
			(end -0.67945 -0.305054)
			(stroke
				(width 0.1)
				(type default)
			)
			(layer "F.Fab")
		)
		(fp_line
			(start -0.67945 -0.305054)
			(end -0.12065 -0.305054)
			(stroke
				(width 0.1)
				(type default)
			)
			(layer "F.Fab")
		)
		(pad "1" smd circle
			(at -0.40005 0 180)
			(size 0 0)
			(layers "F.Cu" "F.Mask" "F.Paste")
			(net "PRSNT_SSD11_FPGA_PCA9555_N")
		)
		(pad "2" smd circle
			(at 0.40005 0 180)
			(size 0 0)
			(layers "F.Cu" "F.Mask" "F.Paste")
			(net "PRSNT_SSD11_FPGA_R_N")
		)
	)
	(footprint ""
		(layer "F.Cu")
		(at 202.430888 -354.629212 90)
		(property "Reference" "R6255"
			(at 0 0 90)
			(layer "F.SilkS")
			(hide yes)
			(effects
				(font
					(size 1.27 1.27)
				)
			)
		)
		(property "Value" ""
			(at 0 0 90)
			(layer "F.Fab")
			(effects
				(font
					(size 1.27 1.27)
				)
			)
		)
		(duplicate_pad_numbers_are_jumpers no)
		(fp_line
			(start 0.7874 -0.4064)
			(end 0.7874 0.4064)
			(stroke
				(width 0.1524)
				(type default)
			)
			(layer "F.SilkS")
		)
		(fp_line
			(start -0.7874 -0.4064)
			(end 0.7874 -0.4064)
			(stroke
				(width 0.1524)
				(type default)
			)
			(layer "F.SilkS")
		)
		(fp_line
			(start 0.7874 0.4064)
			(end -0.7874 0.4064)
			(stroke
				(width 0.1524)
				(type default)
			)
			(layer "F.SilkS")
		)
		(fp_line
			(start -0.7874 0.4064)
			(end -0.7874 -0.4064)
			(stroke
				(width 0.1524)
				(type default)
			)
			(layer "F.SilkS")
		)
		(fp_line
			(start -0.12065 -0.305054)
			(end -0.12065 -0.2794)
			(stroke
				(width 0.1)
				(type default)
			)
			(layer "F.Fab")
		)
		(fp_line
			(start -0.67945 -0.305054)
			(end -0.12065 -0.305054)
			(stroke
				(width 0.1)
				(type default)
			)
			(layer "F.Fab")
		)
		(fp_line
			(start 0.67945 -0.3048)
			(end 0.67945 0.3048)
			(stroke
				(width 0.1)
				(type default)
			)
			(layer "F.Fab")
		)
		(fp_line
			(start 0.12065 -0.3048)
			(end 0.67945 -0.3048)
			(stroke
				(width 0.1)
				(type default)
			)
			(layer "F.Fab")
		)
		(fp_line
			(start 0.12065 -0.2794)
			(end 0.12065 -0.3048)
			(stroke
				(width 0.1)
				(type default)
			)
			(layer "F.Fab")
		)
		(fp_line
			(start -0.12065 -0.2794)
			(end 0.12065 -0.2794)
			(stroke
				(width 0.1)
				(type default)
			)
			(layer "F.Fab")
		)
		(fp_line
			(start 0.120396 0.2794)
			(end -0.12065 0.2794)
			(stroke
				(width 0.1)
				(type default)
			)
			(layer "F.Fab")
		)
		(fp_line
			(start -0.12065 0.2794)
			(end -0.12065 0.3048)
			(stroke
				(width 0.1)
				(type default)
			)
			(layer "F.Fab")
		)
		(fp_line
			(start 0.67945 0.3048)
			(end 0.120396 0.3048)
			(stroke
				(width 0.1)
				(type default)
			)
			(layer "F.Fab")
		)
		(fp_line
			(start 0.120396 0.3048)
			(end 0.120396 0.2794)
			(stroke
				(width 0.1)
				(type default)
			)
			(layer "F.Fab")
		)
		(fp_line
			(start -0.12065 0.3048)
			(end -0.67945 0.3048)
			(stroke
				(width 0.1)
				(type default)
			)
			(layer "F.Fab")
		)
		(fp_line
			(start -0.67945 0.3048)
			(end -0.67945 -0.305054)
			(stroke
				(width 0.1)
				(type default)
			)
			(layer "F.Fab")
		)
		(pad "1" smd circle
			(at -0.40005 0 90)
			(size 0 0)
			(layers "F.Cu" "F.Mask" "F.Paste")
			(net "GND")
		)
		(pad "2" smd circle
			(at 0.40005 0 90)
			(size 0 0)
			(layers "F.Cu" "F.Mask" "F.Paste")
			(net "PD_MB_HSC_ISO_D1_EN")
		)
	)
	(footprint ""
		(layer "F.Cu")
		(at 58.686192 -385.718812 180)
		(property "Reference" "R1833"
			(at 0 0 180)
			(layer "F.SilkS")
			(hide yes)
			(effects
				(font
					(size 1.27 1.27)
				)
			)
		)
		(property "Value" ""
			(at 0 0 180)
			(layer "F.Fab")
			(effects
				(font
					(size 1.27 1.27)
				)
			)
		)
		(duplicate_pad_numbers_are_jumpers no)
		(fp_line
			(start 0.7874 0.4064)
			(end -0.7874 0.4064)
			(stroke
				(width 0.1524)
				(type default)
			)
			(layer "F.SilkS")
		)
		(fp_line
			(start 0.7874 -0.4064)
			(end 0.7874 0.4064)
			(stroke
				(width 0.1524)
				(type default)
			)
			(layer "F.SilkS")
		)
		(fp_line
			(start -0.7874 0.4064)
			(end -0.7874 -0.4064)
			(stroke
				(width 0.1524)
				(type default)
			)
			(layer "F.SilkS")
		)
		(fp_line
			(start -0.7874 -0.4064)
			(end 0.7874 -0.4064)
			(stroke
				(width 0.1524)
				(type default)
			)
			(layer "F.SilkS")
		)
		(fp_line
			(start 0.67945 0.3048)
			(end 0.120396 0.3048)
			(stroke
				(width 0.1)
				(type default)
			)
			(layer "F.Fab")
		)
		(fp_line
			(start 0.67945 -0.3048)
			(end 0.67945 0.3048)
			(stroke
				(width 0.1)
				(type default)
			)
			(layer "F.Fab")
		)
		(fp_line
			(start 0.12065 -0.2794)
			(end 0.12065 -0.3048)
			(stroke
				(width 0.1)
				(type default)
			)
			(layer "F.Fab")
		)
		(fp_line
			(start 0.12065 -0.3048)
			(end 0.67945 -0.3048)
			(stroke
				(width 0.1)
				(type default)
			)
			(layer "F.Fab")
		)
		(fp_line
			(start 0.120396 0.3048)
			(end 0.120396 0.2794)
			(stroke
				(width 0.1)
				(type default)
			)
			(layer "F.Fab")
		)
		(fp_line
			(start 0.120396 0.2794)
			(end -0.12065 0.2794)
			(stroke
				(width 0.1)
				(type default)
			)
			(layer "F.Fab")
		)
		(fp_line
			(start -0.12065 0.3048)
			(end -0.67945 0.3048)
			(stroke
				(width 0.1)
				(type default)
			)
			(layer "F.Fab")
		)
		(fp_line
			(start -0.12065 0.2794)
			(end -0.12065 0.3048)
			(stroke
				(width 0.1)
				(type default)
			)
			(layer "F.Fab")
		)
		(fp_line
			(start -0.12065 -0.2794)
			(end 0.12065 -0.2794)
			(stroke
				(width 0.1)
				(type default)
			)
			(layer "F.Fab")
		)
		(fp_line
			(start -0.12065 -0.305054)
			(end -0.12065 -0.2794)
			(stroke
				(width 0.1)
				(type default)
			)
			(layer "F.Fab")
		)
		(fp_line
			(start -0.67945 0.3048)
			(end -0.67945 -0.305054)
			(stroke
				(width 0.1)
				(type default)
			)
			(layer "F.Fab")
		)
		(fp_line
			(start -0.67945 -0.305054)
			(end -0.12065 -0.305054)
			(stroke
				(width 0.1)
				(type default)
			)
			(layer "F.Fab")
		)
		(pad "1" smd circle
			(at -0.40005 0 180)
			(size 0 0)
			(layers "F.Cu" "F.Mask" "F.Paste")
			(net "GPU_BASE_FPGA_READY_R")
		)
		(pad "2" smd circle
			(at 0.40005 0 180)
			(size 0 0)
			(layers "F.Cu" "F.Mask" "F.Paste")
			(net "GPU_BASE_FPGA_READY")
		)
	)
)
